(kicad_pcb
	(version 20260206)
	(generator "pcbnew")
	(generator_version "10.0")
	(general
		(thickness 1.6)
		(legacy_teardrops no)
	)
	(paper "A4")
	(title_block
		(title "peb — Lightning_PEB_BRD.brd")
		(comment 1 "Lightning (Wiwynn / Facebook NVMe JBOF) / footprints 30-30 of 2563")
	)
	(layers
		(0 "F.Cu" signal "TOP")
		(4 "In1.Cu" signal "L2GND")
		(6 "In2.Cu" signal "L3")
		(8 "In3.Cu" signal "L4VCC")
		(10 "In4.Cu" signal "L5VCC")
		(12 "In5.Cu" signal "L6")
		(14 "In6.Cu" signal "L7GND")
		(2 "B.Cu" signal "BOTTOM")
		(9 "F.Adhes" user "F.Adhesive")
		(11 "B.Adhes" user "B.Adhesive")
		(13 "F.Paste" user "Package Geometry/Pastemask Top")
		(15 "B.Paste" user "Package Geometry/Pastemask Bottom")
		(5 "F.SilkS" user "Ref Des/Silkscreen Top")
		(7 "B.SilkS" user "Ref Des/Silkscreen Bottom")
		(1 "F.Mask" user "Board Geometry/Soldermask Top")
		(3 "B.Mask" user "Board Geometry/Soldermask Bottom")
		(17 "Dwgs.User" user "User.Drawings")
		(19 "Cmts.User" user "User.Comments")
		(21 "Eco1.User" user "User.Eco1")
		(23 "Eco2.User" user "User.Eco2")
		(25 "Edge.Cuts" user "Board Geometry/Outline")
		(27 "Margin" user)
		(31 "F.CrtYd" user "Package Geometry/Place Bound Top")
		(29 "B.CrtYd" user "Package Geometry/Place Bound Bottom")
		(35 "F.Fab" user "Ref Des/Assembly Top")
		(33 "B.Fab" user "Ref Des/Assembly Bottom")
	)
	(footprint ""
		(layer "F.Cu")
		(at 35.768026 -153.97988 -90)
		(property "Reference" "U18"
			(at 0 0 270)
			(layer "F.SilkS")
			(hide yes)
			(effects
				(font
					(size 1.27 1.27)
				)
			)
		)
		(property "Value" "K4B2G1646F-BCK0-GP-U"
			(at -7.925054 0.6858 270)
			(unlocked yes)
			(layer "F.Fab")
			(hide yes)
			(effects
				(font
					(size 1.016 1.016)
					(thickness 0.1524)
				)
			)
		)
		(property "Device Type" "BGA96D075133H48"
			(at -7.925054 -0.8382 270)
			(unlocked yes)
			(layer "F.Fab")
			(hide yes)
			(effects
				(font
					(size 1.016 1.016)
					(thickness 0.1524)
				)
			)
		)
		(duplicate_pad_numbers_are_jumpers no)
		(fp_line
			(start -3.750056 6.649974)
			(end 3.750056 6.649974)
			(stroke
				(width 0.1524)
				(type default)
			)
			(layer "F.SilkS")
		)
		(fp_line
			(start 3.750056 6.649974)
			(end 3.750056 -6.649974)
			(stroke
				(width 0.1524)
				(type default)
			)
			(layer "F.SilkS")
		)
		(fp_line
			(start -4.080256 -5.379974)
			(end -4.080256 -6.980174)
			(stroke
				(width 0.508)
				(type default)
			)
			(layer "F.SilkS")
		)
		(fp_line
			(start -3.750056 -6.649974)
			(end -3.750056 6.649974)
			(stroke
				(width 0.1524)
				(type default)
			)
			(layer "F.SilkS")
		)
		(fp_line
			(start 3.750056 -6.649974)
			(end -3.750056 -6.649974)
			(stroke
				(width 0.1524)
				(type default)
			)
			(layer "F.SilkS")
		)
		(fp_line
			(start -4.080256 -6.980174)
			(end -2.480056 -6.980174)
			(stroke
				(width 0.508)
				(type default)
			)
			(layer "F.SilkS")
		)
		(fp_rect
			(start -3.750056 6.649974)
			(end 3.750056 -6.649974)
			(stroke
				(width 0)
				(type default)
			)
			(fill no)
			(layer "F.CrtYd")
		)
		(fp_poly
			(pts
				(xy -4.750054 7.649972) (xy -4.750054 -7.649972) (xy 4.750054 -7.649972) (xy 4.750054 0.4699) (xy 3.750056 0.4699)
				(xy 3.750056 -6.649974) (xy -3.750056 -6.649974) (xy -3.750056 6.649974) (xy 3.750056 6.649974)
				(xy 3.750056 0.4826) (xy 4.750054 0.4826) (xy 4.750054 7.649972)
			)
			(stroke
				(width 0)
				(type default)
			)
			(fill no)
			(layer "F.CrtYd")
		)
		(fp_rect
			(start -5.750052 8.64997)
			(end 5.750052 -8.64997)
			(stroke
				(width 0)
				(type default)
			)
			(fill no)
			(layer "F.Fab")
		)
		(pad "A1" smd circle
			(at -3.199892 -5.999988 270)
			(size 0.3556 0.3556)
			(layers "F.Cu" "F.Mask" "F.Paste")
			(net "P1V53_STBY")
		)
		(pad "A2" smd circle
			(at -2.400046 -5.999988 270)
			(size 0.3556 0.3556)
			(layers "F.Cu" "F.Mask" "F.Paste")
			(net "MEMDQ_15")
		)
		(pad "A3" smd circle
			(at -1.599946 -5.999988 270)
			(size 0.3556 0.3556)
			(layers "F.Cu" "F.Mask" "F.Paste")
			(net "MEMDQ_14")
		)
		(pad "A7" smd circle
			(at 1.599946 -5.999988 270)
			(size 0.3556 0.3556)
			(layers "F.Cu" "F.Mask" "F.Paste")
			(net "MEMDQ_10")
		)
		(pad "A8" smd circle
			(at 2.400046 -5.999988 270)
			(size 0.3556 0.3556)
			(layers "F.Cu" "F.Mask" "F.Paste")
			(net "P1V53_STBY")
		)
		(pad "A9" smd circle
			(at 3.199892 -5.999988 270)
			(size 0.3556 0.3556)
			(layers "F.Cu" "F.Mask" "F.Paste")
			(net "GND")
		)
		(pad "B1" smd circle
			(at -3.199892 -5.199888 270)
			(size 0.3556 0.3556)
			(layers "F.Cu" "F.Mask" "F.Paste")
			(net "GND")
		)
		(pad "B2" smd circle
			(at -2.400046 -5.199888 270)
			(size 0.3556 0.3556)
			(layers "F.Cu" "F.Mask" "F.Paste")
			(net "P1V53_STBY")
		)
		(pad "B3" smd circle
			(at -1.599946 -5.199888 270)
			(size 0.3556 0.3556)
			(layers "F.Cu" "F.Mask" "F.Paste")
			(net "GND")
		)
		(pad "B7" smd circle
			(at 1.599946 -5.199888 270)
			(size 0.3556 0.3556)
			(layers "F.Cu" "F.Mask" "F.Paste")
			(net "MEMDQS_N1")
		)
		(pad "B8" smd circle
			(at 2.400046 -5.199888 270)
			(size 0.3556 0.3556)
			(layers "F.Cu" "F.Mask" "F.Paste")
			(net "MEMDQ_9")
		)
		(pad "B9" smd circle
			(at 3.199892 -5.199888 270)
			(size 0.3556 0.3556)
			(layers "F.Cu" "F.Mask" "F.Paste")
			(net "GND")
		)
		(pad "C1" smd circle
			(at -3.199892 -4.400042 270)
			(size 0.3556 0.3556)
			(layers "F.Cu" "F.Mask" "F.Paste")
			(net "P1V53_STBY")
		)
		(pad "C2" smd circle
			(at -2.400046 -4.400042 270)
			(size 0.3556 0.3556)
			(layers "F.Cu" "F.Mask" "F.Paste")
			(net "MEMDQ_12")
		)
		(pad "C3" smd circle
			(at -1.599946 -4.400042 270)
			(size 0.3556 0.3556)
			(layers "F.Cu" "F.Mask" "F.Paste")
			(net "MEMDQ_11")
		)
		(pad "C7" smd circle
			(at 1.599946 -4.400042 270)
			(size 0.3556 0.3556)
			(layers "F.Cu" "F.Mask" "F.Paste")
			(net "MEMDQS_P1")
		)
		(pad "C8" smd circle
			(at 2.400046 -4.400042 270)
			(size 0.3556 0.3556)
			(layers "F.Cu" "F.Mask" "F.Paste")
			(net "MEMDQ_13")
		)
		(pad "C9" smd circle
			(at 3.199892 -4.400042 270)
			(size 0.3556 0.3556)
			(layers "F.Cu" "F.Mask" "F.Paste")
			(net "P1V53_STBY")
		)
		(pad "D1" smd circle
			(at -3.199892 -3.599942 270)
			(size 0.3556 0.3556)
			(layers "F.Cu" "F.Mask" "F.Paste")
			(net "GND")
		)
		(pad "D2" smd circle
			(at -2.400046 -3.599942 270)
			(size 0.3556 0.3556)
			(layers "F.Cu" "F.Mask" "F.Paste")
			(net "P1V53_STBY")
		)
		(pad "D3" smd circle
			(at -1.599946 -3.599942 270)
			(size 0.3556 0.3556)
			(layers "F.Cu" "F.Mask" "F.Paste")
			(net "MEMDM_1")
		)
		(pad "D7" smd circle
			(at 1.599946 -3.599942 270)
			(size 0.3556 0.3556)
			(layers "F.Cu" "F.Mask" "F.Paste")
			(net "MEMDQ_8")
		)
		(pad "D8" smd circle
			(at 2.400046 -3.599942 270)
			(size 0.3556 0.3556)
			(layers "F.Cu" "F.Mask" "F.Paste")
			(net "GND")
		)
		(pad "D9" smd circle
			(at 3.199892 -3.599942 270)
			(size 0.3556 0.3556)
			(layers "F.Cu" "F.Mask" "F.Paste")
			(net "P1V53_STBY")
		)
		(pad "E1" smd circle
			(at -3.199892 -2.800096 270)
			(size 0.3556 0.3556)
			(layers "F.Cu" "F.Mask" "F.Paste")
			(net "GND")
		)
		(pad "E2" smd circle
			(at -2.400046 -2.800096 270)
			(size 0.3556 0.3556)
			(layers "F.Cu" "F.Mask" "F.Paste")
			(net "GND")
		)
		(pad "E3" smd circle
			(at -1.599946 -2.800096 270)
			(size 0.3556 0.3556)
			(layers "F.Cu" "F.Mask" "F.Paste")
			(net "MEMDQ_7")
		)
		(pad "E7" smd circle
			(at 1.599946 -2.800096 270)
			(size 0.3556 0.3556)
			(layers "F.Cu" "F.Mask" "F.Paste")
			(net "MEMDM_0")
		)
		(pad "E8" smd circle
			(at 2.400046 -2.800096 270)
			(size 0.3556 0.3556)
			(layers "F.Cu" "F.Mask" "F.Paste")
			(net "GND")
		)
		(pad "E9" smd circle
			(at 3.199892 -2.800096 270)
			(size 0.3556 0.3556)
			(layers "F.Cu" "F.Mask" "F.Paste")
			(net "P1V53_STBY")
		)
		(pad "F1" smd circle
			(at -3.199892 -1.999996 270)
			(size 0.3556 0.3556)
			(layers "F.Cu" "F.Mask" "F.Paste")
			(net "P1V53_STBY")
		)
		(pad "F2" smd circle
			(at -2.400046 -1.999996 270)
			(size 0.3556 0.3556)
			(layers "F.Cu" "F.Mask" "F.Paste")
			(net "MEMDQ_4")
		)
		(pad "F3" smd circle
			(at -1.599946 -1.999996 270)
			(size 0.3556 0.3556)
			(layers "F.Cu" "F.Mask" "F.Paste")
			(net "MEMDQS_P0")
		)
		(pad "F7" smd circle
			(at 1.599946 -1.999996 270)
			(size 0.3556 0.3556)
			(layers "F.Cu" "F.Mask" "F.Paste")
			(net "MEMDQ_3")
		)
		(pad "F8" smd circle
			(at 2.400046 -1.999996 270)
			(size 0.3556 0.3556)
			(layers "F.Cu" "F.Mask" "F.Paste")
			(net "MEMDQ_2")
		)
		(pad "F9" smd circle
			(at 3.199892 -1.999996 270)
			(size 0.3556 0.3556)
			(layers "F.Cu" "F.Mask" "F.Paste")
			(net "GND")
		)
		(pad "G1" smd circle
			(at -3.199892 -1.199896 270)
			(size 0.3556 0.3556)
			(layers "F.Cu" "F.Mask" "F.Paste")
			(net "GND")
		)
		(pad "G2" smd circle
			(at -2.400046 -1.199896 270)
			(size 0.3556 0.3556)
			(layers "F.Cu" "F.Mask" "F.Paste")
			(net "MEMDQ_5")
		)
		(pad "G3" smd circle
			(at -1.599946 -1.199896 270)
			(size 0.3556 0.3556)
			(layers "F.Cu" "F.Mask" "F.Paste")
			(net "MEMDQS_N0")
		)
		(pad "G7" smd circle
			(at 1.599946 -1.199896 270)
			(size 0.3556 0.3556)
			(layers "F.Cu" "F.Mask" "F.Paste")
			(net "P1V53_STBY")
		)
		(pad "G8" smd circle
			(at 2.400046 -1.199896 270)
			(size 0.3556 0.3556)
			(layers "F.Cu" "F.Mask" "F.Paste")
			(net "GND")
		)
		(pad "G9" smd circle
			(at 3.199892 -1.199896 270)
			(size 0.3556 0.3556)
			(layers "F.Cu" "F.Mask" "F.Paste")
			(net "GND")
		)
		(pad "H1" smd circle
			(at -3.199892 -0.40005 270)
			(size 0.3556 0.3556)
			(layers "F.Cu" "F.Mask" "F.Paste")
			(net "DDR_VREF")
		)
		(pad "H2" smd circle
			(at -2.400046 -0.40005 270)
			(size 0.3556 0.3556)
			(layers "F.Cu" "F.Mask" "F.Paste")
			(net "P1V53_STBY")
		)
		(pad "H3" smd circle
			(at -1.599946 -0.40005 270)
			(size 0.3556 0.3556)
			(layers "F.Cu" "F.Mask" "F.Paste")
			(net "MEMDQ_1")
		)
		(pad "H7" smd circle
			(at 1.599946 -0.40005 270)
			(size 0.3556 0.3556)
			(layers "F.Cu" "F.Mask" "F.Paste")
			(net "MEMDQ_0")
		)
		(pad "H8" smd circle
			(at 2.400046 -0.40005 270)
			(size 0.3556 0.3556)
			(layers "F.Cu" "F.Mask" "F.Paste")
			(net "MEMDQ_6")
		)
		(pad "H9" smd circle
			(at 3.199892 -0.40005 270)
			(size 0.3556 0.3556)
			(layers "F.Cu" "F.Mask" "F.Paste")
			(net "P1V53_STBY")
		)
		(pad "J1" smd circle
			(at -3.199892 0.40005 270)
			(size 0.3556 0.3556)
			(layers "F.Cu" "F.Mask" "F.Paste")
			(net "Net_187")
		)
		(pad "J2" smd circle
			(at -2.400046 0.40005 270)
			(size 0.3556 0.3556)
			(layers "F.Cu" "F.Mask" "F.Paste")
			(net "GND")
		)
		(pad "J3" smd circle
			(at -1.599946 0.40005 270)
			(size 0.3556 0.3556)
			(layers "F.Cu" "F.Mask" "F.Paste")
			(net "MEMRASN")
		)
		(pad "J7" smd circle
			(at 1.599946 0.40005 270)
			(size 0.3556 0.3556)
			(layers "F.Cu" "F.Mask" "F.Paste")
			(net "MEMCK_P")
		)
		(pad "J8" smd circle
			(at 2.400046 0.40005 270)
			(size 0.3556 0.3556)
			(layers "F.Cu" "F.Mask" "F.Paste")
			(net "GND")
		)
		(pad "J9" smd circle
			(at 3.199892 0.40005 270)
			(size 0.3556 0.3556)
			(layers "F.Cu" "F.Mask" "F.Paste")
			(net "Net_184")
		)
		(pad "K1" smd circle
			(at -3.199892 1.199896 270)
			(size 0.3556 0.3556)
			(layers "F.Cu" "F.Mask" "F.Paste")
			(net "MEMODT")
		)
		(pad "K2" smd circle
			(at -2.400046 1.199896 270)
			(size 0.3556 0.3556)
			(layers "F.Cu" "F.Mask" "F.Paste")
			(net "P1V53_STBY")
		)
		(pad "K3" smd circle
			(at -1.599946 1.199896 270)
			(size 0.3556 0.3556)
			(layers "F.Cu" "F.Mask" "F.Paste")
			(net "MEMCASN")
		)
		(pad "K7" smd circle
			(at 1.599946 1.199896 270)
			(size 0.3556 0.3556)
			(layers "F.Cu" "F.Mask" "F.Paste")
			(net "MEMCK_N")
		)
		(pad "K8" smd circle
			(at 2.400046 1.199896 270)
			(size 0.3556 0.3556)
			(layers "F.Cu" "F.Mask" "F.Paste")
			(net "P1V53_STBY")
		)
		(pad "K9" smd circle
			(at 3.199892 1.199896 270)
			(size 0.3556 0.3556)
			(layers "F.Cu" "F.Mask" "F.Paste")
			(net "MEMCKE")
		)
		(pad "L1" smd circle
			(at -3.199892 1.999996 270)
			(size 0.3556 0.3556)
			(layers "F.Cu" "F.Mask" "F.Paste")
			(net "Net_188")
		)
		(pad "L2" smd circle
			(at -2.400046 1.999996 270)
			(size 0.3556 0.3556)
			(layers "F.Cu" "F.Mask" "F.Paste")
			(net "MEMCSN")
		)
		(pad "L3" smd circle
			(at -1.599946 1.999996 270)
			(size 0.3556 0.3556)
			(layers "F.Cu" "F.Mask" "F.Paste")
			(net "MEMWEN")
		)
		(pad "L7" smd circle
			(at 1.599946 1.999996 270)
			(size 0.3556 0.3556)
			(layers "F.Cu" "F.Mask" "F.Paste")
			(net "MEMA_10")
		)
		(pad "L8" smd circle
			(at 2.400046 1.999996 270)
			(size 0.3556 0.3556)
			(layers "F.Cu" "F.Mask" "F.Paste")
			(net "PD_ZQ")
		)
		(pad "L9" smd circle
			(at 3.199892 1.999996 270)
			(size 0.3556 0.3556)
			(layers "F.Cu" "F.Mask" "F.Paste")
			(net "Net_186")
		)
		(pad "M1" smd circle
			(at -3.199892 2.800096 270)
			(size 0.3556 0.3556)
			(layers "F.Cu" "F.Mask" "F.Paste")
			(net "GND")
		)
		(pad "M2" smd circle
			(at -2.400046 2.800096 270)
			(size 0.3556 0.3556)
			(layers "F.Cu" "F.Mask" "F.Paste")
			(net "MEMBA_0")
		)
		(pad "M3" smd circle
			(at -1.599946 2.800096 270)
			(size 0.3556 0.3556)
			(layers "F.Cu" "F.Mask" "F.Paste")
			(net "MEMBA_2")
		)
		(pad "M7" smd circle
			(at 1.599946 2.800096 270)
			(size 0.3556 0.3556)
			(layers "F.Cu" "F.Mask" "F.Paste")
			(net "Net_185")
		)
		(pad "M8" smd circle
			(at 2.400046 2.800096 270)
			(size 0.3556 0.3556)
			(layers "F.Cu" "F.Mask" "F.Paste")
			(net "DDR_VREF")
		)
		(pad "M9" smd circle
			(at 3.199892 2.800096 270)
			(size 0.3556 0.3556)
			(layers "F.Cu" "F.Mask" "F.Paste")
			(net "GND")
		)
		(pad "N1" smd circle
			(at -3.199892 3.599942 270)
			(size 0.3556 0.3556)
			(layers "F.Cu" "F.Mask" "F.Paste")
			(net "P1V53_STBY")
		)
		(pad "N2" smd circle
			(at -2.400046 3.599942 270)
			(size 0.3556 0.3556)
			(layers "F.Cu" "F.Mask" "F.Paste")
			(net "MEMA_3")
		)
		(pad "N3" smd circle
			(at -1.599946 3.599942 270)
			(size 0.3556 0.3556)
			(layers "F.Cu" "F.Mask" "F.Paste")
			(net "MEMA_0")
		)
		(pad "N7" smd circle
			(at 1.599946 3.599942 270)
			(size 0.3556 0.3556)
			(layers "F.Cu" "F.Mask" "F.Paste")
			(net "MEMA_12")
		)
		(pad "N8" smd circle
			(at 2.400046 3.599942 270)
			(size 0.3556 0.3556)
			(layers "F.Cu" "F.Mask" "F.Paste")
			(net "MEMBA_1")
		)
		(pad "N9" smd circle
			(at 3.199892 3.599942 270)
			(size 0.3556 0.3556)
			(layers "F.Cu" "F.Mask" "F.Paste")
			(net "P1V53_STBY")
		)
		(pad "P1" smd circle
			(at -3.199892 4.400042 270)
			(size 0.3556 0.3556)
			(layers "F.Cu" "F.Mask" "F.Paste")
			(net "GND")
		)
		(pad "P2" smd circle
			(at -2.400046 4.400042 270)
			(size 0.3556 0.3556)
			(layers "F.Cu" "F.Mask" "F.Paste")
			(net "MEMA_5")
		)
		(pad "P3" smd circle
			(at -1.599946 4.400042 270)
			(size 0.3556 0.3556)
			(layers "F.Cu" "F.Mask" "F.Paste")
			(net "MEMA_2")
		)
		(pad "P7" smd circle
			(at 1.599946 4.400042 270)
			(size 0.3556 0.3556)
			(layers "F.Cu" "F.Mask" "F.Paste")
			(net "MEMA_1")
		)
		(pad "P8" smd circle
			(at 2.400046 4.400042 270)
			(size 0.3556 0.3556)
			(layers "F.Cu" "F.Mask" "F.Paste")
			(net "MEMA_4")
		)
		(pad "P9" smd circle
			(at 3.199892 4.400042 270)
			(size 0.3556 0.3556)
			(layers "F.Cu" "F.Mask" "F.Paste")
			(net "GND")
		)
		(pad "R1" smd circle
			(at -3.199892 5.199888 270)
			(size 0.3556 0.3556)
			(layers "F.Cu" "F.Mask" "F.Paste")
			(net "P1V53_STBY")
		)
		(pad "R2" smd circle
			(at -2.400046 5.199888 270)
			(size 0.3556 0.3556)
			(layers "F.Cu" "F.Mask" "F.Paste")
			(net "MEMA_7")
		)
		(pad "R3" smd circle
			(at -1.599946 5.199888 270)
			(size 0.3556 0.3556)
			(layers "F.Cu" "F.Mask" "F.Paste")
			(net "MEMA_9")
		)
		(pad "R7" smd circle
			(at 1.599946 5.199888 270)
			(size 0.3556 0.3556)
			(layers "F.Cu" "F.Mask" "F.Paste")
			(net "MEMA_11")
		)
		(pad "R8" smd circle
			(at 2.400046 5.199888 270)
			(size 0.3556 0.3556)
			(layers "F.Cu" "F.Mask" "F.Paste")
			(net "MEMA_6")
		)
		(pad "R9" smd circle
			(at 3.199892 5.199888 270)
			(size 0.3556 0.3556)
			(layers "F.Cu" "F.Mask" "F.Paste")
			(net "P1V53_STBY")
		)
		(pad "T1" smd circle
			(at -3.199892 5.999988 270)
			(size 0.3556 0.3556)
			(layers "F.Cu" "F.Mask" "F.Paste")
			(net "GND")
		)
		(pad "T2" smd circle
			(at -2.400046 5.999988 270)
			(size 0.3556 0.3556)
			(layers "F.Cu" "F.Mask" "F.Paste")
			(net "BMC_DDR3_RST_N")
		)
		(pad "T3" smd circle
			(at -1.599946 5.999988 270)
			(size 0.3556 0.3556)
			(layers "F.Cu" "F.Mask" "F.Paste")
			(net "MEMA_13")
		)
		(pad "T7" smd circle
			(at 1.599946 5.999988 270)
			(size 0.3556 0.3556)
			(layers "F.Cu" "F.Mask" "F.Paste")
			(net "MEMA_14")
		)
		(pad "T8" smd circle
			(at 2.400046 5.999988 270)
			(size 0.3556 0.3556)
			(layers "F.Cu" "F.Mask" "F.Paste")
			(net "MEMA_8")
		)
		(pad "T9" smd circle
			(at 3.199892 5.999988 270)
			(size 0.3556 0.3556)
			(layers "F.Cu" "F.Mask" "F.Paste")
			(net "GND")
		)
	)
)
